(kicad_pcb
	(version 20260206)
	(generator "pcbnew")
	(generator_version "10.0")
	(general
		(thickness 1.6)
		(legacy_teardrops no)
	)
	(paper "A4")
	(title_block
		(title "m-2 — Lightning_M.2_BRD.brd")
		(comment 1 "Lightning (Wiwynn / Facebook NVMe JBOF) / footprints 9-16 of 157")
	)
	(layers
		(0 "F.Cu" signal "TOP")
		(4 "In1.Cu" signal "L2GND")
		(6 "In2.Cu" signal "L3")
		(8 "In3.Cu" signal "L4GND")
		(10 "In4.Cu" signal "L5GND")
		(12 "In5.Cu" signal "L6")
		(14 "In6.Cu" signal "L7GND")
		(2 "B.Cu" signal "BOTTOM")
		(9 "F.Adhes" user "F.Adhesive")
		(11 "B.Adhes" user "B.Adhesive")
		(13 "F.Paste" user "Package Geometry/Pastemask Top")
		(15 "B.Paste" user "Package Geometry/Pastemask Bottom")
		(5 "F.SilkS" user "Ref Des/Silkscreen Top")
		(7 "B.SilkS" user "Ref Des/Silkscreen Bottom")
		(1 "F.Mask" user "Board Geometry/Soldermask Top")
		(3 "B.Mask" user "Board Geometry/Soldermask Bottom")
		(17 "Dwgs.User" user "User.Drawings")
		(19 "Cmts.User" user "User.Comments")
		(21 "Eco1.User" user "User.Eco1")
		(23 "Eco2.User" user "User.Eco2")
		(25 "Edge.Cuts" user "Board Geometry/Outline")
		(27 "Margin" user)
		(31 "F.CrtYd" user "Package Geometry/Place Bound Top")
		(29 "B.CrtYd" user "Package Geometry/Place Bound Bottom")
		(35 "F.Fab" user "Ref Des/Assembly Top")
		(33 "B.Fab" user "Ref Des/Assembly Bottom")
	)
	(footprint ""
		(layer "F.Cu")
		(at 63.246 -64.643 180)
		(property "Reference" "C12"
			(at 0 0 180)
			(layer "F.SilkS")
			(hide yes)
			(effects
				(font
					(size 1.27 1.27)
				)
			)
		)
		(property "Value" "SC1U6D3V2KX-9-GP"
			(at 1.1811 -2.7051 180)
			(unlocked yes)
			(layer "F.Fab")
			(hide yes)
			(effects
				(font
					(size 1.016 1.016)
					(thickness 0.1524)
				)
			)
		)
		(property "Device Type" "C402H22"
			(at 1.1811 -4.2291 180)
			(unlocked yes)
			(layer "F.Fab")
			(hide yes)
			(effects
				(font
					(size 1.016 1.016)
					(thickness 0.1524)
				)
			)
		)
		(duplicate_pad_numbers_are_jumpers no)
		(fp_rect
			(start -0.4318 0.9525)
			(end 0.4318 -0.9525)
			(stroke
				(width 0)
				(type default)
			)
			(fill no)
			(layer "F.CrtYd")
		)
		(fp_rect
			(start -0.4318 0.9525)
			(end 0.4318 -0.9525)
			(stroke
				(width 0)
				(type default)
			)
			(fill no)
			(layer "F.Fab")
		)
		(pad "1" smd custom
			(at 0 -0.4445 180)
			(size 0.1524 0.1524)
			(layers "F.Cu" "F.Mask" "F.Paste")
			(net "P3V3_PWR")
			(options
				(clearance outline)
				(anchor circle)
			)
			(primitives
				(gr_poly
					(pts
						(arc
							(start 0.3048 -0.2032)
							(mid 0.275042 -0.275042)
							(end 0.2032 -0.3048)
						)
						(arc
							(start -0.2032 -0.3048)
							(mid -0.275042 -0.275042)
							(end -0.3048 -0.2032)
						)
						(arc
							(start -0.3048 0.2032)
							(mid -0.275042 0.275042)
							(end -0.2032 0.3048)
						)
						(arc
							(start 0.2032 0.3048)
							(mid 0.275042 0.275042)
							(end 0.3048 0.2032)
						)
					)
					(width 0)
					(fill yes)
				)
			)
		)
		(pad "2" smd custom
			(at 0 0.4445 180)
			(size 0.1524 0.1524)
			(layers "F.Cu" "F.Mask" "F.Paste")
			(net "GND")
			(options
				(clearance outline)
				(anchor circle)
			)
			(primitives
				(gr_poly
					(pts
						(arc
							(start 0.3048 -0.2032)
							(mid 0.275042 -0.275042)
							(end 0.2032 -0.3048)
						)
						(arc
							(start -0.2032 -0.3048)
							(mid -0.275042 -0.275042)
							(end -0.3048 -0.2032)
						)
						(arc
							(start -0.3048 0.2032)
							(mid -0.275042 0.275042)
							(end -0.2032 0.3048)
						)
						(arc
							(start 0.2032 0.3048)
							(mid 0.275042 0.275042)
							(end 0.3048 0.2032)
						)
					)
					(width 0)
					(fill yes)
				)
			)
		)
	)
	(footprint ""
		(layer "F.Cu")
		(at 29.21 -78.74)
		(property "Reference" "R38"
			(at 0 0 0)
			(layer "F.SilkS")
			(hide yes)
			(effects
				(font
					(size 1.27 1.27)
				)
			)
		)
		(property "Value" "0R2J-2-GP"
			(at 0.064008 -3.993896 0)
			(unlocked yes)
			(layer "F.Fab")
			(hide yes)
			(effects
				(font
					(size 1.016 1.016)
					(thickness 0.1524)
				)
			)
		)
		(property "Device Type" "R402H16"
			(at 0.064008 -5.517896 0)
			(unlocked yes)
			(layer "F.Fab")
			(hide yes)
			(effects
				(font
					(size 1.016 1.016)
					(thickness 0.1524)
				)
			)
		)
		(duplicate_pad_numbers_are_jumpers no)
		(fp_line
			(start -0.508 -0.9398)
			(end -0.508 0.9398)
			(stroke
				(width 0.1524)
				(type default)
			)
			(layer "F.SilkS")
		)
		(fp_line
			(start 0.508 -0.9398)
			(end -0.508 -0.9398)
			(stroke
				(width 0.1524)
				(type default)
			)
			(layer "F.SilkS")
		)
		(fp_rect
			(start -0.508 0.9398)
			(end 0.508 -0.9398)
			(stroke
				(width 0)
				(type default)
			)
			(fill no)
			(layer "F.CrtYd")
		)
		(fp_rect
			(start -0.508 0.9398)
			(end 0.508 -0.9398)
			(stroke
				(width 0)
				(type default)
			)
			(fill no)
			(layer "F.Fab")
		)
		(pad "1" smd custom
			(at 0 -0.4445)
			(size 0.1397 0.1397)
			(layers "F.Cu" "F.Mask" "F.Paste")
			(net "Z50_SSD_A1_SMB_DATA_R")
			(options
				(clearance outline)
				(anchor circle)
			)
			(primitives
				(gr_poly
					(pts
						(arc
							(start -0.1778 -0.2794)
							(mid -0.249642 -0.249642)
							(end -0.2794 -0.1778)
						)
						(arc
							(start -0.2794 0.1778)
							(mid -0.249642 0.249642)
							(end -0.1778 0.2794)
						)
						(arc
							(start 0.1778 0.2794)
							(mid 0.249642 0.249642)
							(end 0.2794 0.1778)
						)
						(arc
							(start 0.2794 -0.1778)
							(mid 0.249642 -0.249642)
							(end 0.1778 -0.2794)
						)
					)
					(width 0)
					(fill yes)
				)
			)
		)
		(pad "2" smd custom
			(at 0 0.4445)
			(size 0.1397 0.1397)
			(layers "F.Cu" "F.Mask" "F.Paste")
			(net "Z50_SSD_A1_SMB_DATA_LL")
			(options
				(clearance outline)
				(anchor circle)
			)
			(primitives
				(gr_poly
					(pts
						(arc
							(start -0.1778 -0.2794)
							(mid -0.249642 -0.249642)
							(end -0.2794 -0.1778)
						)
						(arc
							(start -0.2794 0.1778)
							(mid -0.249642 0.249642)
							(end -0.1778 0.2794)
						)
						(arc
							(start 0.1778 0.2794)
							(mid 0.249642 0.249642)
							(end 0.2794 0.1778)
						)
						(arc
							(start 0.2794 -0.1778)
							(mid 0.249642 -0.249642)
							(end 0.1778 -0.2794)
						)
					)
					(width 0)
					(fill yes)
				)
			)
		)
	)
	(footprint ""
		(layer "F.Cu")
		(at 53.594 -74.168 -90)
		(property "Reference" "PR27"
			(at 0 0 270)
			(layer "F.SilkS")
			(hide yes)
			(effects
				(font
					(size 1.27 1.27)
				)
			)
		)
		(property "Value" "10R3F-GP"
			(at -0.0254 -2.5146 270)
			(unlocked yes)
			(layer "F.Fab")
			(hide yes)
			(effects
				(font
					(size 1.016 1.016)
					(thickness 0.1524)
				)
			)
		)
		(property "Device Type" "R603H22"
			(at -0.0254 -4.0386 270)
			(unlocked yes)
			(layer "F.Fab")
			(hide yes)
			(effects
				(font
					(size 1.016 1.016)
					(thickness 0.1524)
				)
			)
		)
		(duplicate_pad_numbers_are_jumpers no)
		(fp_line
			(start -0.4826 0)
			(end -0.2032 0)
			(stroke
				(width 0.2032)
				(type default)
			)
			(layer "F.SilkS")
		)
		(fp_line
			(start 0.2032 0)
			(end 0.4826 0)
			(stroke
				(width 0.2032)
				(type default)
			)
			(layer "F.SilkS")
		)
		(fp_rect
			(start -0.5842 1.3335)
			(end 0.5842 -1.3335)
			(stroke
				(width 0)
				(type default)
			)
			(fill no)
			(layer "F.CrtYd")
		)
		(fp_rect
			(start -0.5842 1.3335)
			(end 0.5842 -1.3335)
			(stroke
				(width 0)
				(type default)
			)
			(fill no)
			(layer "F.Fab")
		)
		(pad "1" smd custom
			(at 0 -0.762 270)
			(size 0.2159 0.2159)
			(layers "F.Cu" "F.Mask" "F.Paste")
			(net "P3V3_PWR")
			(options
				(clearance outline)
				(anchor circle)
			)
			(primitives
				(gr_poly
					(pts
						(arc
							(start -0.3302 -0.4318)
							(mid -0.402042 -0.402042)
							(end -0.4318 -0.3302)
						)
						(arc
							(start -0.4318 0.3302)
							(mid -0.402042 0.402042)
							(end -0.3302 0.4318)
						)
						(arc
							(start 0.3302 0.4318)
							(mid 0.402042 0.402042)
							(end 0.4318 0.3302)
						)
						(arc
							(start 0.4318 -0.3302)
							(mid 0.402042 -0.402042)
							(end 0.3302 -0.4318)
						)
					)
					(width 0)
					(fill yes)
				)
			)
		)
		(pad "2" smd custom
			(at 0 0.762 270)
			(size 0.2159 0.2159)
			(layers "F.Cu" "F.Mask" "F.Paste")
			(net "P3V3_DEV_VFB_R")
			(options
				(clearance outline)
				(anchor circle)
			)
			(primitives
				(gr_poly
					(pts
						(arc
							(start -0.3302 -0.4318)
							(mid -0.402042 -0.402042)
							(end -0.4318 -0.3302)
						)
						(arc
							(start -0.4318 0.3302)
							(mid -0.402042 0.402042)
							(end -0.3302 0.4318)
						)
						(arc
							(start 0.3302 0.4318)
							(mid 0.402042 0.402042)
							(end 0.4318 0.3302)
						)
						(arc
							(start 0.4318 -0.3302)
							(mid 0.402042 -0.402042)
							(end 0.3302 -0.4318)
						)
					)
					(width 0)
					(fill yes)
				)
			)
		)
	)
	(footprint ""
		(layer "F.Cu")
		(at 17.526 -76.883006 -90)
		(property "Reference" "PC22"
			(at 0 0 270)
			(layer "F.SilkS")
			(hide yes)
			(effects
				(font
					(size 1.27 1.27)
				)
			)
		)
		(property "Value" "SCD01U25V2KX-3GP"
			(at 1.1811 -2.7051 270)
			(unlocked yes)
			(layer "F.Fab")
			(hide yes)
			(effects
				(font
					(size 1.016 1.016)
					(thickness 0.1524)
				)
			)
		)
		(property "Device Type" "C402H22"
			(at 1.1811 -4.2291 270)
			(unlocked yes)
			(layer "F.Fab")
			(hide yes)
			(effects
				(font
					(size 1.016 1.016)
					(thickness 0.1524)
				)
			)
		)
		(duplicate_pad_numbers_are_jumpers no)
		(fp_rect
			(start -0.4318 0.9525)
			(end 0.4318 -0.9525)
			(stroke
				(width 0)
				(type default)
			)
			(fill no)
			(layer "F.CrtYd")
		)
		(fp_rect
			(start -0.4318 0.9525)
			(end 0.4318 -0.9525)
			(stroke
				(width 0)
				(type default)
			)
			(fill no)
			(layer "F.Fab")
		)
		(pad "1" smd custom
			(at 0 -0.4445 270)
			(size 0.1524 0.1524)
			(layers "F.Cu" "F.Mask" "F.Paste")
			(net "P1V8_PWR")
			(options
				(clearance outline)
				(anchor circle)
			)
			(primitives
				(gr_poly
					(pts
						(arc
							(start 0.3048 -0.2032)
							(mid 0.275042 -0.275042)
							(end 0.2032 -0.3048)
						)
						(arc
							(start -0.2032 -0.3048)
							(mid -0.275042 -0.275042)
							(end -0.3048 -0.2032)
						)
						(arc
							(start -0.3048 0.2032)
							(mid -0.275042 0.275042)
							(end -0.2032 0.3048)
						)
						(arc
							(start 0.2032 0.3048)
							(mid 0.275042 0.275042)
							(end 0.3048 0.2032)
						)
					)
					(width 0)
					(fill yes)
				)
			)
		)
		(pad "2" smd custom
			(at 0 0.4445 270)
			(size 0.1524 0.1524)
			(layers "F.Cu" "F.Mask" "F.Paste")
			(net "P1V8_PWR_FB")
			(options
				(clearance outline)
				(anchor circle)
			)
			(primitives
				(gr_poly
					(pts
						(arc
							(start 0.3048 -0.2032)
							(mid 0.275042 -0.275042)
							(end 0.2032 -0.3048)
						)
						(arc
							(start -0.2032 -0.3048)
							(mid -0.275042 -0.275042)
							(end -0.3048 -0.2032)
						)
						(arc
							(start -0.3048 0.2032)
							(mid -0.275042 0.275042)
							(end -0.2032 0.3048)
						)
						(arc
							(start 0.2032 0.3048)
							(mid 0.275042 0.275042)
							(end 0.3048 0.2032)
						)
					)
					(width 0)
					(fill yes)
				)
			)
		)
	)
	(footprint ""
		(layer "F.Cu")
		(at 32.385 -78.74)
		(property "Reference" "R40"
			(at 0 0 0)
			(layer "F.SilkS")
			(hide yes)
			(effects
				(font
					(size 1.27 1.27)
				)
			)
		)
		(property "Value" "0R2J-2-GP"
			(at 0.064008 -3.993896 0)
			(unlocked yes)
			(layer "F.Fab")
			(hide yes)
			(effects
				(font
					(size 1.016 1.016)
					(thickness 0.1524)
				)
			)
		)
		(property "Device Type" "R402H16"
			(at 0.064008 -5.517896 0)
			(unlocked yes)
			(layer "F.Fab")
			(hide yes)
			(effects
				(font
					(size 1.016 1.016)
					(thickness 0.1524)
				)
			)
		)
		(duplicate_pad_numbers_are_jumpers no)
		(fp_line
			(start -0.508 -0.9398)
			(end -0.508 0.9398)
			(stroke
				(width 0.1524)
				(type default)
			)
			(layer "F.SilkS")
		)
		(fp_line
			(start 0.508 -0.9398)
			(end -0.508 -0.9398)
			(stroke
				(width 0.1524)
				(type default)
			)
			(layer "F.SilkS")
		)
		(fp_rect
			(start -0.508 0.9398)
			(end 0.508 -0.9398)
			(stroke
				(width 0)
				(type default)
			)
			(fill no)
			(layer "F.CrtYd")
		)
		(fp_rect
			(start -0.508 0.9398)
			(end 0.508 -0.9398)
			(stroke
				(width 0)
				(type default)
			)
			(fill no)
			(layer "F.Fab")
		)
		(pad "1" smd custom
			(at 0 -0.4445)
			(size 0.1397 0.1397)
			(layers "F.Cu" "F.Mask" "F.Paste")
			(net "Z50_SSD_B1_SMB_DATA_R")
			(options
				(clearance outline)
				(anchor circle)
			)
			(primitives
				(gr_poly
					(pts
						(arc
							(start -0.1778 -0.2794)
							(mid -0.249642 -0.249642)
							(end -0.2794 -0.1778)
						)
						(arc
							(start -0.2794 0.1778)
							(mid -0.249642 0.249642)
							(end -0.1778 0.2794)
						)
						(arc
							(start 0.1778 0.2794)
							(mid 0.249642 0.249642)
							(end 0.2794 0.1778)
						)
						(arc
							(start 0.2794 -0.1778)
							(mid 0.249642 -0.249642)
							(end 0.1778 -0.2794)
						)
					)
					(width 0)
					(fill yes)
				)
			)
		)
		(pad "2" smd custom
			(at 0 0.4445)
			(size 0.1397 0.1397)
			(layers "F.Cu" "F.Mask" "F.Paste")
			(net "Z50_SSD_B1_SMB_DATA_LL")
			(options
				(clearance outline)
				(anchor circle)
			)
			(primitives
				(gr_poly
					(pts
						(arc
							(start -0.1778 -0.2794)
							(mid -0.249642 -0.249642)
							(end -0.2794 -0.1778)
						)
						(arc
							(start -0.2794 0.1778)
							(mid -0.249642 0.249642)
							(end -0.1778 0.2794)
						)
						(arc
							(start 0.1778 0.2794)
							(mid 0.249642 0.249642)
							(end 0.2794 0.1778)
						)
						(arc
							(start 0.2794 -0.1778)
							(mid 0.249642 -0.249642)
							(end 0.1778 -0.2794)
						)
					)
					(width 0)
					(fill yes)
				)
			)
		)
	)
	(footprint ""
		(layer "F.Cu")
		(at 59.817 -17.018 -90)
		(property "Reference" "C21"
			(at 0 0 270)
			(layer "F.SilkS")
			(hide yes)
			(effects
				(font
					(size 1.27 1.27)
				)
			)
		)
		(property "Value" "SCD1U16V2KX-3GP"
			(at 1.1811 -2.7051 270)
			(unlocked yes)
			(layer "F.Fab")
			(hide yes)
			(effects
				(font
					(size 1.016 1.016)
					(thickness 0.1524)
				)
			)
		)
		(property "Device Type" "C402H22"
			(at 1.1811 -4.2291 270)
			(unlocked yes)
			(layer "F.Fab")
			(hide yes)
			(effects
				(font
					(size 1.016 1.016)
					(thickness 0.1524)
				)
			)
		)
		(duplicate_pad_numbers_are_jumpers no)
		(fp_rect
			(start -0.4318 0.9525)
			(end 0.4318 -0.9525)
			(stroke
				(width 0)
				(type default)
			)
			(fill no)
			(layer "F.CrtYd")
		)
		(fp_rect
			(start -0.4318 0.9525)
			(end 0.4318 -0.9525)
			(stroke
				(width 0)
				(type default)
			)
			(fill no)
			(layer "F.Fab")
		)
		(pad "1" smd custom
			(at 0 -0.4445 270)
			(size 0.1524 0.1524)
			(layers "F.Cu" "F.Mask" "F.Paste")
			(net "P3V3_PWR")
			(options
				(clearance outline)
				(anchor circle)
			)
			(primitives
				(gr_poly
					(pts
						(arc
							(start 0.3048 -0.2032)
							(mid 0.275042 -0.275042)
							(end 0.2032 -0.3048)
						)
						(arc
							(start -0.2032 -0.3048)
							(mid -0.275042 -0.275042)
							(end -0.3048 -0.2032)
						)
						(arc
							(start -0.3048 0.2032)
							(mid -0.275042 0.275042)
							(end -0.2032 0.3048)
						)
						(arc
							(start 0.2032 0.3048)
							(mid 0.275042 0.275042)
							(end 0.3048 0.2032)
						)
					)
					(width 0)
					(fill yes)
				)
			)
		)
		(pad "2" smd custom
			(at 0 0.4445 270)
			(size 0.1524 0.1524)
			(layers "F.Cu" "F.Mask" "F.Paste")
			(net "GND")
			(options
				(clearance outline)
				(anchor circle)
			)
			(primitives
				(gr_poly
					(pts
						(arc
							(start 0.3048 -0.2032)
							(mid 0.275042 -0.275042)
							(end 0.2032 -0.3048)
						)
						(arc
							(start -0.2032 -0.3048)
							(mid -0.275042 -0.275042)
							(end -0.3048 -0.2032)
						)
						(arc
							(start -0.3048 0.2032)
							(mid -0.275042 0.275042)
							(end -0.2032 0.3048)
						)
						(arc
							(start 0.2032 0.3048)
							(mid 0.275042 0.275042)
							(end 0.3048 0.2032)
						)
					)
					(width 0)
					(fill yes)
				)
			)
		)
	)
	(footprint ""
		(layer "F.Cu")
		(at 59.817 -19.05 -90)
		(property "Reference" "C22"
			(at 0 0 270)
			(layer "F.SilkS")
			(hide yes)
			(effects
				(font
					(size 1.27 1.27)
				)
			)
		)
		(property "Value" "SCD1U16V2KX-3GP"
			(at 1.1811 -2.7051 270)
			(unlocked yes)
			(layer "F.Fab")
			(hide yes)
			(effects
				(font
					(size 1.016 1.016)
					(thickness 0.1524)
				)
			)
		)
		(property "Device Type" "C402H22"
			(at 1.1811 -4.2291 270)
			(unlocked yes)
			(layer "F.Fab")
			(hide yes)
			(effects
				(font
					(size 1.016 1.016)
					(thickness 0.1524)
				)
			)
		)
		(duplicate_pad_numbers_are_jumpers no)
		(fp_rect
			(start -0.4318 0.9525)
			(end 0.4318 -0.9525)
			(stroke
				(width 0)
				(type default)
			)
			(fill no)
			(layer "F.CrtYd")
		)
		(fp_rect
			(start -0.4318 0.9525)
			(end 0.4318 -0.9525)
			(stroke
				(width 0)
				(type default)
			)
			(fill no)
			(layer "F.Fab")
		)
		(pad "1" smd custom
			(at 0 -0.4445 270)
			(size 0.1524 0.1524)
			(layers "F.Cu" "F.Mask" "F.Paste")
			(net "P3V3_PWR")
			(options
				(clearance outline)
				(anchor circle)
			)
			(primitives
				(gr_poly
					(pts
						(arc
							(start 0.3048 -0.2032)
							(mid 0.275042 -0.275042)
							(end 0.2032 -0.3048)
						)
						(arc
							(start -0.2032 -0.3048)
							(mid -0.275042 -0.275042)
							(end -0.3048 -0.2032)
						)
						(arc
							(start -0.3048 0.2032)
							(mid -0.275042 0.275042)
							(end -0.2032 0.3048)
						)
						(arc
							(start 0.2032 0.3048)
							(mid 0.275042 0.275042)
							(end 0.3048 0.2032)
						)
					)
					(width 0)
					(fill yes)
				)
			)
		)
		(pad "2" smd custom
			(at 0 0.4445 270)
			(size 0.1524 0.1524)
			(layers "F.Cu" "F.Mask" "F.Paste")
			(net "GND")
			(options
				(clearance outline)
				(anchor circle)
			)
			(primitives
				(gr_poly
					(pts
						(arc
							(start 0.3048 -0.2032)
							(mid 0.275042 -0.275042)
							(end 0.2032 -0.3048)
						)
						(arc
							(start -0.2032 -0.3048)
							(mid -0.275042 -0.275042)
							(end -0.3048 -0.2032)
						)
						(arc
							(start -0.3048 0.2032)
							(mid -0.275042 0.275042)
							(end -0.2032 0.3048)
						)
						(arc
							(start 0.2032 0.3048)
							(mid 0.275042 0.275042)
							(end 0.3048 0.2032)
						)
					)
					(width 0)
					(fill yes)
				)
			)
		)
	)
	(footprint ""
		(layer "F.Cu")
		(at 59.817 -34.163 -90)
		(property "Reference" "C33"
			(at 0 0 270)
			(layer "F.SilkS")
			(hide yes)
			(effects
				(font
					(size 1.27 1.27)
				)
			)
		)
		(property "Value" "SCD1U16V2KX-3GP"
			(at 1.1811 -2.7051 270)
			(unlocked yes)
			(layer "F.Fab")
			(hide yes)
			(effects
				(font
					(size 1.016 1.016)
					(thickness 0.1524)
				)
			)
		)
		(property "Device Type" "C402H22"
			(at 1.1811 -4.2291 270)
			(unlocked yes)
			(layer "F.Fab")
			(hide yes)
			(effects
				(font
					(size 1.016 1.016)
					(thickness 0.1524)
				)
			)
		)
		(duplicate_pad_numbers_are_jumpers no)
		(fp_rect
			(start -0.4318 0.9525)
			(end 0.4318 -0.9525)
			(stroke
				(width 0)
				(type default)
			)
			(fill no)
			(layer "F.CrtYd")
		)
		(fp_rect
			(start -0.4318 0.9525)
			(end 0.4318 -0.9525)
			(stroke
				(width 0)
				(type default)
			)
			(fill no)
			(layer "F.Fab")
		)
		(pad "1" smd custom
			(at 0 -0.4445 270)
			(size 0.1524 0.1524)
			(layers "F.Cu" "F.Mask" "F.Paste")
			(net "P3V3_PWR")
			(options
				(clearance outline)
				(anchor circle)
			)
			(primitives
				(gr_poly
					(pts
						(arc
							(start 0.3048 -0.2032)
							(mid 0.275042 -0.275042)
							(end 0.2032 -0.3048)
						)
						(arc
							(start -0.2032 -0.3048)
							(mid -0.275042 -0.275042)
							(end -0.3048 -0.2032)
						)
						(arc
							(start -0.3048 0.2032)
							(mid -0.275042 0.275042)
							(end -0.2032 0.3048)
						)
						(arc
							(start 0.2032 0.3048)
							(mid 0.275042 0.275042)
							(end 0.3048 0.2032)
						)
					)
					(width 0)
					(fill yes)
				)
			)
		)
		(pad "2" smd custom
			(at 0 0.4445 270)
			(size 0.1524 0.1524)
			(layers "F.Cu" "F.Mask" "F.Paste")
			(net "GND")
			(options
				(clearance outline)
				(anchor circle)
			)
			(primitives
				(gr_poly
					(pts
						(arc
							(start 0.3048 -0.2032)
							(mid 0.275042 -0.275042)
							(end 0.2032 -0.3048)
						)
						(arc
							(start -0.2032 -0.3048)
							(mid -0.275042 -0.275042)
							(end -0.3048 -0.2032)
						)
						(arc
							(start -0.3048 0.2032)
							(mid -0.275042 0.275042)
							(end -0.2032 0.3048)
						)
						(arc
							(start 0.2032 0.3048)
							(mid 0.275042 0.275042)
							(end 0.3048 0.2032)
						)
					)
					(width 0)
					(fill yes)
				)
			)
		)
	)
)
